(kicad_pcb
	(version 20260206)
	(generator "pcbnew")
	(generator_version "10.0")
	(general
		(thickness 1.6)
		(legacy_teardrops no)
	)
	(paper "A4")
	(title_block
		(title "v1-chassis-manager — T6M_CM_d_v01_1031_1645.brd")
		(comment 1 "Open CloudServer (Microsoft) / footprint 513 of 2512 (U32), pads 1-69 of 69")
	)
	(layers
		(0 "F.Cu" signal "TOP")
		(4 "In1.Cu" signal "GND1")
		(6 "In2.Cu" signal "IN1")
		(8 "In3.Cu" signal "VCC1")
		(10 "In4.Cu" signal "VCC2")
		(12 "In5.Cu" signal "GND2")
		(14 "In6.Cu" signal "IN2")
		(16 "In7.Cu" signal "IN3")
		(18 "In8.Cu" signal "GND3")
		(2 "B.Cu" signal "BOTTOM")
		(9 "F.Adhes" user "F.Adhesive")
		(11 "B.Adhes" user "B.Adhesive")
		(13 "F.Paste" user "Package Geometry/Pastemask Top")
		(15 "B.Paste" user "Package Geometry/Pastemask Bottom")
		(5 "F.SilkS" user "Ref Des/Silkscreen Top")
		(7 "B.SilkS" user "Ref Des/Silkscreen Bottom")
		(1 "F.Mask" user "Board Geometry/Soldermask Top")
		(3 "B.Mask" user "Board Geometry/Soldermask Bottom")
		(17 "Dwgs.User" user "User.Drawings")
		(19 "Cmts.User" user "User.Comments")
		(21 "Eco1.User" user "User.Eco1")
		(23 "Eco2.User" user "User.Eco2")
		(25 "Edge.Cuts" user "Board Geometry/Outline")
		(27 "Margin" user)
		(31 "F.CrtYd" user "Package Geometry/Place Bound Top")
		(29 "B.CrtYd" user "Package Geometry/Place Bound Bottom")
		(35 "F.Fab" user "Ref Des/Assembly Top")
		(33 "B.Fab" user "Ref Des/Assembly Bottom")
	)
	(footprint ""
		(layer "F.Cu")
		(at 167.243252 -100.93579)
		(property "Reference" "U32"
			(at 0.1143 -6.103366 0)
			(unlocked yes)
			(layer "F.SilkS")
			(effects
				(font
					(size 0.7874 0.5842)
					(thickness 0.1524)
				)
				(justify left)
			)
		)
		(property "Value" ""
			(at 0 0 0)
			(layer "F.Fab")
			(effects
				(font
					(size 1.27 1.27)
				)
			)
		)
		(duplicate_pad_numbers_are_jumpers no)
		(pad "1" smd rect
			(at -3.992118 -3.199892 90)
			(size 0.1778 1.016)
			(layers "F.Cu" "F.Mask" "F.Paste")
			(net "USB_NODE1_SMI_L")
		)
		(pad "2" smd rect
			(at -3.903218 -2.800096 90)
			(size 0.1778 1.1938)
			(layers "F.Cu" "F.Mask" "F.Paste")
			(net "N34379705")
		)
		(pad "3" smd rect
			(at -3.903218 -2.400046 90)
			(size 0.1778 1.1938)
			(layers "F.Cu" "F.Mask" "F.Paste")
			(net "USB_WAKE_N")
		)
		(pad "4" smd rect
			(at -3.903218 -1.999996 90)
			(size 0.1778 1.1938)
			(layers "F.Cu" "F.Mask" "F.Paste")
			(net "CLK_100M_USB_NODE1_DP")
		)
		(pad "5" smd rect
			(at -3.903218 -1.599946 90)
			(size 0.1778 1.1938)
			(layers "F.Cu" "F.Mask" "F.Paste")
			(net "CLK_100M_USB_NODE1_DN")
		)
		(pad "6" smd rect
			(at -3.903218 -1.199896 90)
			(size 0.1778 1.1938)
			(layers "F.Cu" "F.Mask" "F.Paste")
			(net "P3V3_USB_NODE1")
		)
		(pad "7" smd rect
			(at -3.903218 -0.8001 90)
			(size 0.1778 1.1938)
			(layers "F.Cu" "F.Mask" "F.Paste")
			(net "P2E_CPU_USB_NODE1_RX_C_DP")
		)
		(pad "8" smd rect
			(at -3.903218 -0.40005 90)
			(size 0.1778 1.1938)
			(layers "F.Cu" "F.Mask" "F.Paste")
			(net "P2E_CPU_USB_NODE1_RX_C_DN")
		)
		(pad "9" smd rect
			(at -3.903218 0 90)
			(size 0.1778 1.1938)
			(layers "F.Cu" "F.Mask" "F.Paste")
			(net "P1V05_NODE1")
		)
		(pad "10" smd rect
			(at -3.903218 0.40005 90)
			(size 0.1778 1.1938)
			(layers "F.Cu" "F.Mask" "F.Paste")
			(net "P2E_CPU_USB_NODE1_TX_DP")
		)
		(pad "11" smd rect
			(at -3.903218 0.8001 90)
			(size 0.1778 1.1938)
			(layers "F.Cu" "F.Mask" "F.Paste")
			(net "P2E_CPU_USB_NODE1_TX_DN")
		)
		(pad "12" smd rect
			(at -3.903218 1.199896 90)
			(size 0.1778 1.1938)
			(layers "F.Cu" "F.Mask" "F.Paste")
			(net "P1V05_NODE1")
		)
		(pad "13" smd rect
			(at -3.903218 1.599946 90)
			(size 0.1778 1.1938)
			(layers "F.Cu" "F.Mask" "F.Paste")
			(net "USB_NODE1_PECREQ_L")
		)
		(pad "14" smd rect
			(at -3.903218 1.999996 90)
			(size 0.1778 1.1938)
			(layers "F.Cu" "F.Mask" "F.Paste")
			(net "FM_CPLD_NODE1_USB_PONRST_L")
		)
		(pad "15" smd rect
			(at -3.903218 2.400046 90)
			(size 0.1778 1.1938)
			(layers "F.Cu" "F.Mask" "F.Paste")
			(net "P3V3_NODE1")
		)
		(pad "16" smd rect
			(at -3.903218 2.800096 90)
			(size 0.1778 1.1938)
			(layers "F.Cu" "F.Mask" "F.Paste")
			(net "SPI_USB_NODE1_SI")
		)
		(pad "17" smd rect
			(at -3.992118 3.199892 90)
			(size 0.1778 1.016)
			(layers "F.Cu" "F.Mask" "F.Paste")
			(net "SPI_USB_NODE1_CSB_R_L")
		)
		(pad "18" smd rect
			(at -3.199892 3.992118)
			(size 0.1778 1.016)
			(layers "F.Cu" "F.Mask" "F.Paste")
			(net "SPI_USB_NODE1_CLK_R")
		)
		(pad "19" smd rect
			(at -2.800096 3.903218)
			(size 0.1778 1.1938)
			(layers "F.Cu" "F.Mask" "F.Paste")
			(net "SPI_USB_NODE1_R_SO")
		)
		(pad "20" smd rect
			(at -2.400046 3.903218)
			(size 0.1778 1.1938)
			(layers "F.Cu" "F.Mask" "F.Paste")
			(net "USB_OC_PU")
		)
		(pad "21" smd rect
			(at -1.999996 3.903218)
			(size 0.1778 1.1938)
			(layers "F.Cu" "F.Mask" "F.Paste")
			(net "Net_2263")
		)
		(pad "22" smd rect
			(at -1.599946 3.903218)
			(size 0.1778 1.1938)
			(layers "F.Cu" "F.Mask" "F.Paste")
			(net "USB_OC_PU")
		)
		(pad "23" smd rect
			(at -1.199896 3.903218)
			(size 0.1778 1.1938)
			(layers "F.Cu" "F.Mask" "F.Paste")
			(net "Net_2264")
		)
		(pad "24" smd rect
			(at -0.8001 3.903218)
			(size 0.1778 1.1938)
			(layers "F.Cu" "F.Mask" "F.Paste")
			(net "USB_OC_PU")
		)
		(pad "25" smd rect
			(at -0.40005 3.903218)
			(size 0.1778 1.1938)
			(layers "F.Cu" "F.Mask" "F.Paste")
			(net "Net_2265")
		)
		(pad "26" smd rect
			(at 0 3.903218)
			(size 0.1778 1.1938)
			(layers "F.Cu" "F.Mask" "F.Paste")
			(net "USB_OC_PU")
		)
		(pad "27" smd rect
			(at 0.40005 3.903218)
			(size 0.1778 1.1938)
			(layers "F.Cu" "F.Mask" "F.Paste")
			(net "Net_2266")
		)
		(pad "28" smd rect
			(at 0.8001 3.903218)
			(size 0.1778 1.1938)
			(layers "F.Cu" "F.Mask" "F.Paste")
			(net "P1V05_NODE1")
		)
		(pad "29" smd rect
			(at 1.199896 3.903218)
			(size 0.1778 1.1938)
			(layers "F.Cu" "F.Mask" "F.Paste")
			(net "P3V3_NODE1")
		)
		(pad "30" smd rect
			(at 1.599946 3.903218)
			(size 0.1778 1.1938)
			(layers "F.Cu" "F.Mask" "F.Paste")
			(net "USB_NODE1_XTA2")
		)
		(pad "31" smd rect
			(at 1.999996 3.903218)
			(size 0.1778 1.1938)
			(layers "F.Cu" "F.Mask" "F.Paste")
			(net "USB_NODE1_XTA1")
		)
		(pad "32" smd rect
			(at 2.400046 3.903218)
			(size 0.1778 1.1938)
			(layers "F.Cu" "F.Mask" "F.Paste")
			(net "P3V3_USB_NODE1")
		)
		(pad "33" smd rect
			(at 2.800096 3.903218)
			(size 0.1778 1.1938)
			(layers "F.Cu" "F.Mask" "F.Paste")
			(net "USB_NODE1_RREF")
		)
		(pad "34" smd rect
			(at 3.199892 3.992118)
			(size 0.1778 1.016)
			(layers "F.Cu" "F.Mask" "F.Paste")
			(net "GND")
		)
		(pad "35" smd rect
			(at 3.992118 3.199892 90)
			(size 0.1778 1.016)
			(layers "F.Cu" "F.Mask" "F.Paste")
			(net "TP_U3TXDP1")
		)
		(pad "36" smd rect
			(at 3.903218 2.800096 90)
			(size 0.1778 1.1938)
			(layers "F.Cu" "F.Mask" "F.Paste")
			(net "TP_U3TXDN1")
		)
		(pad "37" smd rect
			(at 3.903218 2.400046 90)
			(size 0.1778 1.1938)
			(layers "F.Cu" "F.Mask" "F.Paste")
			(net "P1V05_NODE1")
		)
		(pad "38" smd rect
			(at 3.903218 1.999996 90)
			(size 0.1778 1.1938)
			(layers "F.Cu" "F.Mask" "F.Paste")
			(net "GND")
		)
		(pad "39" smd rect
			(at 3.903218 1.599946 90)
			(size 0.1778 1.1938)
			(layers "F.Cu" "F.Mask" "F.Paste")
			(net "GND")
		)
		(pad "40" smd rect
			(at 3.903218 1.199896 90)
			(size 0.1778 1.1938)
			(layers "F.Cu" "F.Mask" "F.Paste")
			(net "P3V3_NODE1")
		)
		(pad "41" smd rect
			(at 3.903218 0.8001 90)
			(size 0.1778 1.1938)
			(layers "F.Cu" "F.Mask" "F.Paste")
			(net "USB0_DP")
		)
		(pad "42" smd rect
			(at 3.903218 0.40005 90)
			(size 0.1778 1.1938)
			(layers "F.Cu" "F.Mask" "F.Paste")
			(net "USB0_DN")
		)
		(pad "43" smd rect
			(at 3.903218 0 90)
			(size 0.1778 1.1938)
			(layers "F.Cu" "F.Mask" "F.Paste")
			(net "P1V05_NODE1")
		)
		(pad "44" smd rect
			(at 3.903218 -0.40005 90)
			(size 0.1778 1.1938)
			(layers "F.Cu" "F.Mask" "F.Paste")
			(net "TP_U3TXDP2")
		)
		(pad "45" smd rect
			(at 3.903218 -0.8001 90)
			(size 0.1778 1.1938)
			(layers "F.Cu" "F.Mask" "F.Paste")
			(net "TP_U3TXDN2")
		)
		(pad "46" smd rect
			(at 3.903218 -1.199896 90)
			(size 0.1778 1.1938)
			(layers "F.Cu" "F.Mask" "F.Paste")
			(net "P1V05_NODE1")
		)
		(pad "47" smd rect
			(at 3.903218 -1.599946 90)
			(size 0.1778 1.1938)
			(layers "F.Cu" "F.Mask" "F.Paste")
			(net "GND")
		)
		(pad "48" smd rect
			(at 3.903218 -1.999996 90)
			(size 0.1778 1.1938)
			(layers "F.Cu" "F.Mask" "F.Paste")
			(net "GND")
		)
		(pad "49" smd rect
			(at 3.903218 -2.400046 90)
			(size 0.1778 1.1938)
			(layers "F.Cu" "F.Mask" "F.Paste")
			(net "P3V3_NODE1")
		)
		(pad "50" smd rect
			(at 3.903218 -2.800096 90)
			(size 0.1778 1.1938)
			(layers "F.Cu" "F.Mask" "F.Paste")
			(net "USB1_DP")
		)
		(pad "51" smd rect
			(at 3.992118 -3.199892 90)
			(size 0.1778 1.016)
			(layers "F.Cu" "F.Mask" "F.Paste")
			(net "USB1_DN")
		)
		(pad "52" smd rect
			(at 3.199892 -3.992118)
			(size 0.1778 1.016)
			(layers "F.Cu" "F.Mask" "F.Paste")
			(net "TP_U3TXDP3")
		)
		(pad "53" smd rect
			(at 2.800096 -3.903218)
			(size 0.1778 1.1938)
			(layers "F.Cu" "F.Mask" "F.Paste")
			(net "TP_U3TXDN3")
		)
		(pad "54" smd rect
			(at 2.400046 -3.903218)
			(size 0.1778 1.1938)
			(layers "F.Cu" "F.Mask" "F.Paste")
			(net "P1V05_NODE1")
		)
		(pad "55" smd rect
			(at 1.999996 -3.903218)
			(size 0.1778 1.1938)
			(layers "F.Cu" "F.Mask" "F.Paste")
			(net "GND")
		)
		(pad "56" smd rect
			(at 1.599946 -3.903218)
			(size 0.1778 1.1938)
			(layers "F.Cu" "F.Mask" "F.Paste")
			(net "GND")
		)
		(pad "57" smd rect
			(at 1.199896 -3.903218)
			(size 0.1778 1.1938)
			(layers "F.Cu" "F.Mask" "F.Paste")
			(net "P3V3_NODE1")
		)
		(pad "58" smd rect
			(at 0.8001 -3.903218)
			(size 0.1778 1.1938)
			(layers "F.Cu" "F.Mask" "F.Paste")
			(net "USB2_DP")
		)
		(pad "59" smd rect
			(at 0.40005 -3.903218)
			(size 0.1778 1.1938)
			(layers "F.Cu" "F.Mask" "F.Paste")
			(net "USB2_DN")
		)
		(pad "60" smd rect
			(at 0 -3.903218)
			(size 0.1778 1.1938)
			(layers "F.Cu" "F.Mask" "F.Paste")
			(net "P1V05_NODE1")
		)
		(pad "61" smd rect
			(at -0.40005 -3.903218)
			(size 0.1778 1.1938)
			(layers "F.Cu" "F.Mask" "F.Paste")
			(net "TP_U3TXDP4")
		)
		(pad "62" smd rect
			(at -0.8001 -3.903218)
			(size 0.1778 1.1938)
			(layers "F.Cu" "F.Mask" "F.Paste")
			(net "TP_U3TXDN4")
		)
		(pad "63" smd rect
			(at -1.199896 -3.903218)
			(size 0.1778 1.1938)
			(layers "F.Cu" "F.Mask" "F.Paste")
			(net "P1V05_NODE1")
		)
		(pad "64" smd rect
			(at -1.599946 -3.903218)
			(size 0.1778 1.1938)
			(layers "F.Cu" "F.Mask" "F.Paste")
			(net "GND")
		)
		(pad "65" smd rect
			(at -1.999996 -3.903218)
			(size 0.1778 1.1938)
			(layers "F.Cu" "F.Mask" "F.Paste")
			(net "GND")
		)
		(pad "66" smd rect
			(at -2.400046 -3.903218)
			(size 0.1778 1.1938)
			(layers "F.Cu" "F.Mask" "F.Paste")
			(net "P3V3_NODE1")
		)
		(pad "67" smd rect
			(at -2.800096 -3.903218)
			(size 0.1778 1.1938)
			(layers "F.Cu" "F.Mask" "F.Paste")
			(net "USB3_DP")
		)
		(pad "68" smd rect
			(at -3.199892 -3.992118)
			(size 0.1778 1.016)
			(layers "F.Cu" "F.Mask" "F.Paste")
			(net "USB3_DN")
		)
		(pad "TH" smd rect
			(at 0 0)
			(size 6.1976 6.1976)
			(layers "F.Cu" "F.Mask" "F.Paste")
			(net "GND")
		)
	)
)
